# T6G (Grand Teton) — schematic netlist excerpt (pin names and nets, part order shuffled) for the footprints in the layout excerpt that follows; sources: Cadence DE-HDL packaged netlist, KiCad conversion of 04192023_DAF0TMB3IC0_F0TG_MB_C_brd_V02_OCP.brd

PR6608  Q_RES  1 1% CHIP  pkg 0402LF  page 362 : A = P0V9_RETIMER_CPU0_VCC ; B = P3V3_AUX
C5013  Q_CAP  1000PF 50V 5% X7R  pkg 0402  page 200 : A = PVDDCR_CPU1_P0_SMB_ALERT ; B = GND

(kicad_pcb
	(version 20260206)
	(generator "pcbnew")
	(generator_version "10.0")
	(general
		(thickness 1.6)
		(legacy_teardrops no)
	)
	(paper "A4")
	(title_block
		(title "04192023_DAF0TMB3IC0_F0TG_MB_C_brd_V02_OCP.brd")
		(comment 1 "Grand Teton / footprints 4572-4573 of 8354")
	)
	(layers
		(0 "F.Cu" signal "TOP")
		(4 "In1.Cu" signal "GND")
		(6 "In2.Cu" signal "IN1")
		(8 "In3.Cu" signal "GND1")
		(10 "In4.Cu" signal "IN2")
		(12 "In5.Cu" signal "GND2")
		(14 "In6.Cu" signal "IN3")
		(16 "In7.Cu" signal "GND3")
		(18 "In8.Cu" signal "VCC")
		(20 "In9.Cu" signal "VCC1")
		(22 "In10.Cu" signal "GND4")
		(24 "In11.Cu" signal "IN4")
		(26 "In12.Cu" signal "GND5")
		(28 "In13.Cu" signal "IN5")
		(30 "In14.Cu" signal "GND6")
		(32 "In15.Cu" signal "IN6")
		(34 "In16.Cu" signal "GND7")
		(2 "B.Cu" signal "BOTTOM")
		(9 "F.Adhes" user "F.Adhesive")
		(11 "B.Adhes" user "B.Adhesive")
		(13 "F.Paste" user "Package Geometry/Pastemask Top")
		(15 "B.Paste" user "Package Geometry/Pastemask Bottom")
		(5 "F.SilkS" user "Ref Des/Silkscreen Top")
		(7 "B.SilkS" user "Ref Des/Silkscreen Bottom")
		(1 "F.Mask" user "Board Geometry/Soldermask Top")
		(3 "B.Mask" user "Board Geometry/Soldermask Bottom")
		(17 "Dwgs.User" user "User.Drawings")
		(19 "Cmts.User" user "User.Comments")
		(21 "Eco1.User" user "User.Eco1")
		(23 "Eco2.User" user "User.Eco2")
		(25 "Edge.Cuts" user "Board Geometry/Outline")
		(27 "Margin" user)
		(31 "F.CrtYd" user "Package Geometry/Place Bound Top")
		(29 "B.CrtYd" user "Package Geometry/Place Bound Bottom")
		(35 "F.Fab" user "Ref Des/Assembly Top")
		(33 "B.Fab" user "Ref Des/Assembly Bottom")
	)
	(footprint ""
		(layer "F.Cu")
		(at 449.443602 -429.25111)
		(property "Reference" "PR6608"
			(at 0 0 0)
			(layer "F.SilkS")
			(hide yes)
			(effects
				(font
					(size 1.27 1.27)
				)
			)
		)
		(property "Value" ""
			(at 0 0 0)
			(layer "F.Fab")
			(effects
				(font
					(size 1.27 1.27)
				)
			)
		)
		(duplicate_pad_numbers_are_jumpers no)
		(fp_line
			(start -0.7874 -0.4064)
			(end 0.7874 -0.4064)
			(stroke
				(width 0.1524)
				(type default)
			)
			(layer "F.SilkS")
		)
		(fp_line
			(start -0.7874 0.4064)
			(end -0.7874 -0.4064)
			(stroke
				(width 0.1524)
				(type default)
			)
			(layer "F.SilkS")
		)
		(fp_line
			(start 0.7874 -0.4064)
			(end 0.7874 0.4064)
			(stroke
				(width 0.1524)
				(type default)
			)
			(layer "F.SilkS")
		)
		(fp_line
			(start 0.7874 0.4064)
			(end -0.7874 0.4064)
			(stroke
				(width 0.1524)
				(type default)
			)
			(layer "F.SilkS")
		)
		(fp_line
			(start -0.67945 -0.305054)
			(end -0.12065 -0.305054)
			(stroke
				(width 0.1)
				(type default)
			)
			(layer "F.Fab")
		)
		(fp_line
			(start -0.67945 0.3048)
			(end -0.67945 -0.305054)
			(stroke
				(width 0.1)
				(type default)
			)
			(layer "F.Fab")
		)
		(fp_line
			(start -0.12065 -0.305054)
			(end -0.12065 -0.2794)
			(stroke
				(width 0.1)
				(type default)
			)
			(layer "F.Fab")
		)
		(fp_line
			(start -0.12065 -0.2794)
			(end 0.12065 -0.2794)
			(stroke
				(width 0.1)
				(type default)
			)
			(layer "F.Fab")
		)
		(fp_line
			(start -0.12065 0.2794)
			(end -0.12065 0.3048)
			(stroke
				(width 0.1)
				(type default)
			)
			(layer "F.Fab")
		)
		(fp_line
			(start -0.12065 0.3048)
			(end -0.67945 0.3048)
			(stroke
				(width 0.1)
				(type default)
			)
			(layer "F.Fab")
		)
		(fp_line
			(start 0.120396 0.2794)
			(end -0.12065 0.2794)
			(stroke
				(width 0.1)
				(type default)
			)
			(layer "F.Fab")
		)
		(fp_line
			(start 0.120396 0.3048)
			(end 0.120396 0.2794)
			(stroke
				(width 0.1)
				(type default)
			)
			(layer "F.Fab")
		)
		(fp_line
			(start 0.12065 -0.3048)
			(end 0.67945 -0.3048)
			(stroke
				(width 0.1)
				(type default)
			)
			(layer "F.Fab")
		)
		(fp_line
			(start 0.12065 -0.2794)
			(end 0.12065 -0.3048)
			(stroke
				(width 0.1)
				(type default)
			)
			(layer "F.Fab")
		)
		(fp_line
			(start 0.67945 -0.3048)
			(end 0.67945 0.3048)
			(stroke
				(width 0.1)
				(type default)
			)
			(layer "F.Fab")
		)
		(fp_line
			(start 0.67945 0.3048)
			(end 0.120396 0.3048)
			(stroke
				(width 0.1)
				(type default)
			)
			(layer "F.Fab")
		)
		(pad "1" smd circle
			(at -0.40005 0)
			(size 0 0)
			(layers "F.Cu" "F.Mask" "F.Paste")
			(net "P0V9_RETIMER_CPU0_VCC")
		)
		(pad "2" smd circle
			(at 0.40005 0)
			(size 0 0)
			(layers "F.Cu" "F.Mask" "F.Paste")
			(net "P3V3_AUX")
		)
	)
	(footprint ""
		(layer "F.Cu")
		(at 302.133 -365.125 180)
		(property "Reference" "C5013"
			(at 0 0 180)
			(layer "F.SilkS")
			(hide yes)
			(effects
				(font
					(size 1.27 1.27)
				)
			)
		)
		(property "Value" ""
			(at 0 0 180)
			(layer "F.Fab")
			(effects
				(font
					(size 1.27 1.27)
				)
			)
		)
		(duplicate_pad_numbers_are_jumpers no)
		(fp_line
			(start 0.7874 0.4064)
			(end -0.7874 0.4064)
			(stroke
				(width 0.1524)
				(type default)
			)
			(layer "F.SilkS")
		)
		(fp_line
			(start 0.7874 -0.4064)
			(end 0.7874 0.4064)
			(stroke
				(width 0.1524)
				(type default)
			)
			(layer "F.SilkS")
		)
		(fp_line
			(start -0.7874 0.4064)
			(end -0.7874 -0.4064)
			(stroke
				(width 0.1524)
				(type default)
			)
			(layer "F.SilkS")
		)
		(fp_line
			(start -0.7874 -0.4064)
			(end 0.7874 -0.4064)
			(stroke
				(width 0.1524)
				(type default)
			)
			(layer "F.SilkS")
		)
		(fp_line
			(start 0.67945 0.3048)
			(end 0.120396 0.3048)
			(stroke
				(width 0.1)
				(type default)
			)
			(layer "F.Fab")
		)
		(fp_line
			(start 0.67945 -0.3048)
			(end 0.67945 0.3048)
			(stroke
				(width 0.1)
				(type default)
			)
			(layer "F.Fab")
		)
		(fp_line
			(start 0.12065 -0.2794)
			(end 0.12065 -0.3048)
			(stroke
				(width 0.1)
				(type default)
			)
			(layer "F.Fab")
		)
		(fp_line
			(start 0.12065 -0.3048)
			(end 0.67945 -0.3048)
			(stroke
				(width 0.1)
				(type default)
			)
			(layer "F.Fab")
		)
		(fp_line
			(start 0.120396 0.3048)
			(end 0.120396 0.2794)
			(stroke
				(width 0.1)
				(type default)
			)
			(layer "F.Fab")
		)
		(fp_line
			(start 0.120396 0.2794)
			(end -0.12065 0.2794)
			(stroke
				(width 0.1)
				(type default)
			)
			(layer "F.Fab")
		)
		(fp_line
			(start -0.12065 0.3048)
			(end -0.67945 0.3048)
			(stroke
				(width 0.1)
				(type default)
			)
			(layer "F.Fab")
		)
		(fp_line
			(start -0.12065 0.2794)
			(end -0.12065 0.3048)
			(stroke
				(width 0.1)
				(type default)
			)
			(layer "F.Fab")
		)
		(fp_line
			(start -0.12065 -0.2794)
			(end 0.12065 -0.2794)
			(stroke
				(width 0.1)
				(type default)
			)
			(layer "F.Fab")
		)
		(fp_line
			(start -0.12065 -0.305054)
			(end -0.12065 -0.2794)
			(stroke
				(width 0.1)
				(type default)
			)
			(layer "F.Fab")
		)
		(fp_line
			(start -0.67945 0.3048)
			(end -0.67945 -0.305054)
			(stroke
				(width 0.1)
				(type default)
			)
			(layer "F.Fab")
		)
		(fp_line
			(start -0.67945 -0.305054)
			(end -0.12065 -0.305054)
			(stroke
				(width 0.1)
				(type default)
			)
			(layer "F.Fab")
		)
		(pad "1" smd circle
			(at -0.40005 0 180)
			(size 0 0)
			(layers "F.Cu" "F.Mask" "F.Paste")
			(net "PVDDCR_CPU1_P0_SMB_ALERT")
		)
		(pad "2" smd circle
			(at 0.40005 0 180)
			(size 0 0)
			(layers "F.Cu" "F.Mask" "F.Paste")
			(net "GND")
		)
	)
)
